# T6G (Grand Teton) — schematic netlist excerpt (pin names and nets, part order shuffled) for the footprints in the layout excerpt that follows; sources: Cadence DE-HDL packaged netlist, KiCad conversion of 04192023_DAF0TMB3IC0_F0TG_MB_C_brd_V02_OCP.brd

X8  TP_TDR_4P_FTS  TP_TDR_4P_DIP EMPTY  pkg TH  page 260
  S1  = TDR_DIFF_80_IN1_DN
  P1  = T1_GND
  P2  = T1_GND
  S2  = TDR_DIFF_80_IN1_DP

R6264  Q_RES  0 5% CHIP  pkg 0402LF  page 178 : A = USB_HUB2_TI_USB_DM_DN3_MRP_VDD33 ; B = P3V3_AUX_CPU0_USB2_AVDD33

(kicad_pcb
	(version 20260206)
	(generator "pcbnew")
	(generator_version "10.0")
	(general
		(thickness 1.6)
		(legacy_teardrops no)
	)
	(paper "A4")
	(title_block
		(title "04192023_DAF0TMB3IC0_F0TG_MB_C_brd_V02_OCP.brd")
		(comment 1 "Grand Teton / footprints 2028-2029 of 8354")
	)
	(layers
		(0 "F.Cu" signal "TOP")
		(4 "In1.Cu" signal "GND")
		(6 "In2.Cu" signal "IN1")
		(8 "In3.Cu" signal "GND1")
		(10 "In4.Cu" signal "IN2")
		(12 "In5.Cu" signal "GND2")
		(14 "In6.Cu" signal "IN3")
		(16 "In7.Cu" signal "GND3")
		(18 "In8.Cu" signal "VCC")
		(20 "In9.Cu" signal "VCC1")
		(22 "In10.Cu" signal "GND4")
		(24 "In11.Cu" signal "IN4")
		(26 "In12.Cu" signal "GND5")
		(28 "In13.Cu" signal "IN5")
		(30 "In14.Cu" signal "GND6")
		(32 "In15.Cu" signal "IN6")
		(34 "In16.Cu" signal "GND7")
		(2 "B.Cu" signal "BOTTOM")
		(9 "F.Adhes" user "F.Adhesive")
		(11 "B.Adhes" user "B.Adhesive")
		(13 "F.Paste" user "Package Geometry/Pastemask Top")
		(15 "B.Paste" user "Package Geometry/Pastemask Bottom")
		(5 "F.SilkS" user "Ref Des/Silkscreen Top")
		(7 "B.SilkS" user "Ref Des/Silkscreen Bottom")
		(1 "F.Mask" user "Board Geometry/Soldermask Top")
		(3 "B.Mask" user "Board Geometry/Soldermask Bottom")
		(17 "Dwgs.User" user "User.Drawings")
		(19 "Cmts.User" user "User.Comments")
		(21 "Eco1.User" user "User.Eco1")
		(23 "Eco2.User" user "User.Eco2")
		(25 "Edge.Cuts" user "Board Geometry/Outline")
		(27 "Margin" user)
		(31 "F.CrtYd" user "Package Geometry/Place Bound Top")
		(29 "B.CrtYd" user "Package Geometry/Place Bound Bottom")
		(35 "F.Fab" user "Ref Des/Assembly Top")
		(33 "B.Fab" user "Ref Des/Assembly Bottom")
	)
	(footprint ""
		(layer "F.Cu")
		(at 514.718808 -298.391326 90)
		(property "Reference" "X8"
			(at -1.99009 1.316736 0)
			(unlocked yes)
			(layer "F.SilkS")
			(effects
				(font
					(size 0.7874 0.5842)
					(thickness 0.1524)
				)
				(justify left)
			)
		)
		(property "Value" ""
			(at 0 0 90)
			(layer "F.Fab")
			(effects
				(font
					(size 1.27 1.27)
				)
			)
		)
		(property "User Part Number" "N_A"
			(at 1.30175 1.27 180)
			(unlocked yes)
			(layer "Cmts.User")
			(hide yes)
			(effects
				(font
					(size 0.635 0.4064)
					(thickness 0.1524)
				)
			)
		)
		(property "Device Type" "TP_TDR_4P_FTS_TH-TP_TDR_4P_DIP,EMPTY,TP15"
			(at 1.30175 1.27 180)
			(unlocked yes)
			(layer "F.Fab")
			(hide yes)
			(effects
				(font
					(size 0.635 0.4064)
					(thickness 0.1524)
				)
			)
		)
		(duplicate_pad_numbers_are_jumpers no)
		(fp_line
			(start 2.54 -1.27)
			(end 0 -1.27)
			(stroke
				(width 0.1524)
				(type default)
			)
			(layer "F.SilkS")
		)
		(fp_line
			(start 0 -1.27)
			(end 0 -0.635)
			(stroke
				(width 0.1524)
				(type default)
			)
			(layer "F.SilkS")
		)
		(fp_line
			(start 2.54 -1.1303)
			(end 2.54 -1.27)
			(stroke
				(width 0.1524)
				(type default)
			)
			(layer "F.SilkS")
		)
		(fp_line
			(start 0 0.635)
			(end 0 1.905)
			(stroke
				(width 0.1524)
				(type default)
			)
			(layer "F.SilkS")
		)
		(fp_line
			(start 2.54 1.4097)
			(end 2.54 1.1303)
			(stroke
				(width 0.1524)
				(type default)
			)
			(layer "F.SilkS")
		)
		(fp_line
			(start 0 3.175)
			(end 0 3.81)
			(stroke
				(width 0.1524)
				(type default)
			)
			(layer "F.SilkS")
		)
		(fp_line
			(start 2.54 3.81)
			(end 2.54 3.6703)
			(stroke
				(width 0.1524)
				(type default)
			)
			(layer "F.SilkS")
		)
		(fp_line
			(start 0 3.81)
			(end 2.54 3.81)
			(stroke
				(width 0.1524)
				(type default)
			)
			(layer "F.SilkS")
		)
		(fp_poly
			(pts
				(xy -0.761746 0) (xy -2.285746 0.762) (xy -2.285746 -0.762)
			)
			(stroke
				(width 0)
				(type default)
			)
			(fill yes)
			(layer "F.SilkS")
		)
		(fp_line
			(start 2.54 -1.27)
			(end 0 -1.27)
			(stroke
				(width 0.1)
				(type default)
			)
			(layer "F.Fab")
		)
		(fp_line
			(start 0 -1.27)
			(end 0 3.81)
			(stroke
				(width 0.1)
				(type default)
			)
			(layer "F.Fab")
		)
		(fp_line
			(start 2.54 3.81)
			(end 2.54 -1.27)
			(stroke
				(width 0.1)
				(type default)
			)
			(layer "F.Fab")
		)
		(fp_line
			(start 0 3.81)
			(end 2.54 3.81)
			(stroke
				(width 0.1)
				(type default)
			)
			(layer "F.Fab")
		)
		(fp_poly
			(pts
				(xy -0.761746 0) (xy -2.285746 -0.762) (xy -2.285746 0.762)
			)
			(stroke
				(width 0)
				(type default)
			)
			(fill yes)
			(layer "F.Fab")
		)
		(pad "1" thru_hole circle
			(at 0 0 90)
			(size 1.0033 1.0033)
			(drill 0.249936)
			(layers "*.Cu" "*.Mask")
			(remove_unused_layers no)
			(net "TDR_DIFF_80_IN1_DN")
			(clearance 0.10795)
			(thermal_gap 0.10795)
			(padstack
				(mode front_inner_back)
				(layer "Inner"
					(shape circle)
					(size 0.8001 0.8001)
					(clearance 0.1524)
				)
				(layer "B.Cu"
					(shape circle)
					(size 1.0033 1.0033)
					(clearance 0.10795)
				)
			)
		)
		(pad "2" thru_hole circle
			(at 2.54 0 90)
			(size 1.9939 1.9939)
			(drill 0.249936)
			(layers "*.Cu" "*.Mask")
			(remove_unused_layers no)
			(net "T1_GND")
			(clearance 0.10795)
			(thermal_gap 0.10795)
			(padstack
				(mode front_inner_back)
				(layer "Inner"
					(shape circle)
					(size 0.8001 0.8001)
					(clearance 0.1524)
				)
				(layer "B.Cu"
					(shape circle)
					(size 1.9939 1.9939)
					(clearance 0.10795)
				)
			)
		)
		(pad "3" thru_hole circle
			(at 2.54 2.54 90)
			(size 1.9939 1.9939)
			(drill 0.249936)
			(layers "*.Cu" "*.Mask")
			(remove_unused_layers no)
			(net "T1_GND")
			(clearance 0.10795)
			(thermal_gap 0.10795)
			(padstack
				(mode front_inner_back)
				(layer "Inner"
					(shape circle)
					(size 0.8001 0.8001)
					(clearance 0.1524)
				)
				(layer "B.Cu"
					(shape circle)
					(size 1.9939 1.9939)
					(clearance 0.10795)
				)
			)
		)
		(pad "4" thru_hole circle
			(at 0 2.54 90)
			(size 1.0033 1.0033)
			(drill 0.249936)
			(layers "*.Cu" "*.Mask")
			(remove_unused_layers no)
			(net "TDR_DIFF_80_IN1_DP")
			(clearance 0.10795)
			(thermal_gap 0.10795)
			(padstack
				(mode front_inner_back)
				(layer "Inner"
					(shape circle)
					(size 0.8001 0.8001)
					(clearance 0.1524)
				)
				(layer "B.Cu"
					(shape circle)
					(size 1.0033 1.0033)
					(clearance 0.10795)
				)
			)
		)
	)
	(footprint ""
		(layer "F.Cu")
		(at 120.68175 -25.545796)
		(property "Reference" "R6264"
			(at 0 0 0)
			(layer "F.SilkS")
			(hide yes)
			(effects
				(font
					(size 1.27 1.27)
				)
			)
		)
		(property "Value" ""
			(at 0 0 0)
			(layer "F.Fab")
			(effects
				(font
					(size 1.27 1.27)
				)
			)
		)
		(duplicate_pad_numbers_are_jumpers no)
		(fp_line
			(start -0.7874 -0.4064)
			(end 0.7874 -0.4064)
			(stroke
				(width 0.1524)
				(type default)
			)
			(layer "F.SilkS")
		)
		(fp_line
			(start -0.7874 0.4064)
			(end -0.7874 -0.4064)
			(stroke
				(width 0.1524)
				(type default)
			)
			(layer "F.SilkS")
		)
		(fp_line
			(start 0.7874 -0.4064)
			(end 0.7874 0.4064)
			(stroke
				(width 0.1524)
				(type default)
			)
			(layer "F.SilkS")
		)
		(fp_line
			(start 0.7874 0.4064)
			(end -0.7874 0.4064)
			(stroke
				(width 0.1524)
				(type default)
			)
			(layer "F.SilkS")
		)
		(fp_line
			(start -0.67945 -0.305054)
			(end -0.12065 -0.305054)
			(stroke
				(width 0.1)
				(type default)
			)
			(layer "F.Fab")
		)
		(fp_line
			(start -0.67945 0.3048)
			(end -0.67945 -0.305054)
			(stroke
				(width 0.1)
				(type default)
			)
			(layer "F.Fab")
		)
		(fp_line
			(start -0.12065 -0.305054)
			(end -0.12065 -0.2794)
			(stroke
				(width 0.1)
				(type default)
			)
			(layer "F.Fab")
		)
		(fp_line
			(start -0.12065 -0.2794)
			(end 0.12065 -0.2794)
			(stroke
				(width 0.1)
				(type default)
			)
			(layer "F.Fab")
		)
		(fp_line
			(start -0.12065 0.2794)
			(end -0.12065 0.3048)
			(stroke
				(width 0.1)
				(type default)
			)
			(layer "F.Fab")
		)
		(fp_line
			(start -0.12065 0.3048)
			(end -0.67945 0.3048)
			(stroke
				(width 0.1)
				(type default)
			)
			(layer "F.Fab")
		)
		(fp_line
			(start 0.120396 0.2794)
			(end -0.12065 0.2794)
			(stroke
				(width 0.1)
				(type default)
			)
			(layer "F.Fab")
		)
		(fp_line
			(start 0.120396 0.3048)
			(end 0.120396 0.2794)
			(stroke
				(width 0.1)
				(type default)
			)
			(layer "F.Fab")
		)
		(fp_line
			(start 0.12065 -0.3048)
			(end 0.67945 -0.3048)
			(stroke
				(width 0.1)
				(type default)
			)
			(layer "F.Fab")
		)
		(fp_line
			(start 0.12065 -0.2794)
			(end 0.12065 -0.3048)
			(stroke
				(width 0.1)
				(type default)
			)
			(layer "F.Fab")
		)
		(fp_line
			(start 0.67945 -0.3048)
			(end 0.67945 0.3048)
			(stroke
				(width 0.1)
				(type default)
			)
			(layer "F.Fab")
		)
		(fp_line
			(start 0.67945 0.3048)
			(end 0.120396 0.3048)
			(stroke
				(width 0.1)
				(type default)
			)
			(layer "F.Fab")
		)
		(pad "1" smd circle
			(at -0.40005 0)
			(size 0 0)
			(layers "F.Cu" "F.Mask" "F.Paste")
			(net "USB_HUB2_TI_USB_DM_DN3_MRP_VDD33")
		)
		(pad "2" smd circle
			(at 0.40005 0)
			(size 0 0)
			(layers "F.Cu" "F.Mask" "F.Paste")
			(net "P3V3_AUX_CPU0_USB2_AVDD33")
		)
	)
)
